(kicad_pcb
	(version 20241229)
	(generator "pcbnew")
	(generator_version "9.0")
	(general
		(thickness 1.599998)
		(legacy_teardrops no)
	)
	(paper "A4")
	(title_block
		(date "2023-02-12")
		(rev "1.1.5")
		(comment 9 "footprint 3 of 473 (J9), pads 1-91 of 264")
	)
	(layers
		(0 "F.Cu" signal)
		(4 "In1.Cu" power "In1.GND")
		(6 "In2.Cu" signal)
		(8 "In3.Cu" power "In3.GND")
		(10 "In4.Cu" power "In4.VCC")
		(12 "In5.Cu" signal)
		(14 "In6.Cu" power "In6.VCC")
		(2 "B.Cu" signal)
		(9 "F.Adhes" user "F.Adhesive")
		(11 "B.Adhes" user "B.Adhesive")
		(13 "F.Paste" user)
		(15 "B.Paste" user)
		(5 "F.SilkS" user "F.Silkscreen")
		(7 "B.SilkS" user "B.Silkscreen")
		(1 "F.Mask" user)
		(3 "B.Mask" user)
		(17 "Dwgs.User" user "User.Drawings")
		(19 "Cmts.User" user "User.Comments")
		(21 "Eco1.User" user "User.Eco1")
		(23 "Eco2.User" user "User.Eco2")
		(25 "Edge.Cuts" user)
		(27 "Margin" user)
		(31 "F.CrtYd" user "F.Courtyard")
		(29 "B.CrtYd" user "B.Courtyard")
		(35 "F.Fab" user)
		(33 "B.Fab" user)
	)
	(footprint "antmicro-footprints:Bus_DDR4_SODIMM_TE_2309409"
		(layer "F.Cu")
		(at 150.411328 66.671157 180)
		(descr "260 pin DDR4 SODIMM Right Angle Socket, 5.2 mm (0.205 in) Stack Height, https://www.te.com/usa-en/product-2309409-1.html")
		(property "Reference" "J9"
			(at -36.726 -13.477 180)
			(layer "F.SilkS")
			(effects
				(font
					(size 0.7 0.7)
					(thickness 0.15)
				)
				(justify left bottom)
			)
		)
		(property "Value" "Bus_DDR4_SODIMM_TE_2309409"
			(at -8.1 -7.7 180)
			(layer "F.Fab")
			(effects
				(font
					(size 0.7 0.7)
					(thickness 0.15)
				)
				(justify left bottom)
			)
		)
		(property "Description" "Memory Card Connector, DDR4, SODIMM, Cam-In Locking, 260 Contacts, Copper Alloy"
			(at 0 0 180)
			(layer "F.Fab")
			(hide yes)
			(effects
				(font
					(size 1.27 1.27)
					(thickness 0.15)
				)
			)
		)
		(property "Author" "Antmicro"
			(at 300.822656 133.342314 0)
			(layer "F.Fab")
			(hide yes)
			(effects
				(font
					(size 1 1)
					(thickness 0.15)
				)
			)
		)
		(property "License" "Apache-2.0"
			(at 300.822656 133.342314 0)
			(layer "F.Fab")
			(hide yes)
			(effects
				(font
					(size 1 1)
					(thickness 0.15)
				)
			)
		)
		(property "MPN" "2309409-1"
			(at 300.822656 133.342314 0)
			(layer "F.Fab")
			(hide yes)
			(effects
				(font
					(size 1 1)
					(thickness 0.15)
				)
			)
		)
		(property "Manufacturer" "TE Connectivity"
			(at 300.822656 133.342314 0)
			(layer "F.Fab")
			(hide yes)
			(effects
				(font
					(size 1 1)
					(thickness 0.15)
				)
			)
		)
		(sheetname "SO-DIMM")
		(sheetfile "sodimm.kicad_sch")
		(attr smd)
		(pad "" np_thru_hole circle
			(at -34.402 -8.077 180)
			(size 1.15 1.15)
			(drill 1.15)
			(layers "*.Cu" "*.Mask")
		)
		(pad "" np_thru_hole circle
			(at 34.399 -8.077 180)
			(size 1.65 1.65)
			(drill 1.65)
			(layers "*.Cu" "*.Mask")
		)
		(pad "1" smd rect
			(at 33.374 -12.176 180)
			(size 0.3 1.75)
			(layers "F.Cu" "F.Mask" "F.Paste")
			(net 5 "GND")
			(pinfunction "1")
			(pintype "passive")
		)
		(pad "2" smd rect
			(at 33.124 -3.979 180)
			(size 0.3 1.75)
			(layers "F.Cu" "F.Mask" "F.Paste")
			(net 5 "GND")
			(pinfunction "2")
			(pintype "passive")
		)
		(pad "3" smd rect
			(at 32.874 -12.176 180)
			(size 0.3 1.75)
			(layers "F.Cu" "F.Mask" "F.Paste")
			(net 5 "GND")
			(pinfunction "3")
			(pintype "passive")
		)
		(pad "4" smd rect
			(at 32.624 -3.979 180)
			(size 0.3 1.75)
			(layers "F.Cu" "F.Mask" "F.Paste")
			(net 5 "GND")
			(pinfunction "4")
			(pintype "passive")
		)
		(pad "5" smd rect
			(at 32.374 -12.176 180)
			(size 0.3 1.75)
			(layers "F.Cu" "F.Mask" "F.Paste")
			(net 5 "GND")
			(pinfunction "5")
			(pintype "passive")
		)
		(pad "6" smd rect
			(at 32.124 -3.979 180)
			(size 0.3 1.75)
			(layers "F.Cu" "F.Mask" "F.Paste")
			(net 5 "GND")
			(pinfunction "6")
			(pintype "passive")
		)
		(pad "7" smd rect
			(at 31.874 -12.176 180)
			(size 0.3 1.75)
			(layers "F.Cu" "F.Mask" "F.Paste")
			(net 5 "GND")
			(pinfunction "7")
			(pintype "passive")
		)
		(pad "8" smd rect
			(at 31.624 -3.979 180)
			(size 0.3 1.75)
			(layers "F.Cu" "F.Mask" "F.Paste")
			(net 5 "GND")
			(pinfunction "8")
			(pintype "passive")
		)
		(pad "9" smd rect
			(at 31.374 -12.176 180)
			(size 0.3 1.75)
			(layers "F.Cu" "F.Mask" "F.Paste")
			(net 5 "GND")
			(pinfunction "9")
			(pintype "passive")
		)
		(pad "10" smd rect
			(at 31.124 -3.979 180)
			(size 0.3 1.75)
			(layers "F.Cu" "F.Mask" "F.Paste")
			(net 5 "GND")
			(pinfunction "10")
			(pintype "passive")
		)
		(pad "11" smd rect
			(at 30.874 -12.176 180)
			(size 0.3 1.75)
			(layers "F.Cu" "F.Mask" "F.Paste")
			(net 5 "GND")
			(pinfunction "11")
			(pintype "passive")
		)
		(pad "12" smd rect
			(at 30.624 -3.979 180)
			(size 0.3 1.75)
			(layers "F.Cu" "F.Mask" "F.Paste")
			(net 5 "GND")
			(pinfunction "12")
			(pintype "passive")
		)
		(pad "13" smd rect
			(at 30.374 -12.176 180)
			(size 0.3 1.75)
			(layers "F.Cu" "F.Mask" "F.Paste")
			(net 5 "GND")
			(pinfunction "13")
			(pintype "passive")
		)
		(pad "14" smd rect
			(at 30.124 -3.979 180)
			(size 0.3 1.75)
			(layers "F.Cu" "F.Mask" "F.Paste")
			(net 5 "GND")
			(pinfunction "14")
			(pintype "passive")
		)
		(pad "15" smd rect
			(at 29.874 -12.176 180)
			(size 0.3 1.75)
			(layers "F.Cu" "F.Mask" "F.Paste")
			(net 5 "GND")
			(pinfunction "15")
			(pintype "passive")
		)
		(pad "16" smd rect
			(at 29.624 -3.979 180)
			(size 0.3 1.75)
			(layers "F.Cu" "F.Mask" "F.Paste")
			(net 5 "GND")
			(pinfunction "16")
			(pintype "passive")
		)
		(pad "17" smd rect
			(at 29.374 -12.176 180)
			(size 0.3 1.75)
			(layers "F.Cu" "F.Mask" "F.Paste")
			(net 5 "GND")
			(pinfunction "17")
			(pintype "passive")
		)
		(pad "18" smd rect
			(at 29.124 -3.979 180)
			(size 0.3 1.75)
			(layers "F.Cu" "F.Mask" "F.Paste")
			(net 5 "GND")
			(pinfunction "18")
			(pintype "passive")
		)
		(pad "19" smd rect
			(at 28.874 -12.176 180)
			(size 0.3 1.75)
			(layers "F.Cu" "F.Mask" "F.Paste")
			(net 5 "GND")
			(pinfunction "19")
			(pintype "passive")
		)
		(pad "20" smd rect
			(at 28.624 -3.979 180)
			(size 0.3 1.75)
			(layers "F.Cu" "F.Mask" "F.Paste")
			(net 5 "GND")
			(pinfunction "20")
			(pintype "passive")
		)
		(pad "21" smd rect
			(at 28.374 -12.176 180)
			(size 0.3 1.75)
			(layers "F.Cu" "F.Mask" "F.Paste")
			(net 5 "GND")
			(pinfunction "21")
			(pintype "passive")
		)
		(pad "22" smd rect
			(at 28.124 -3.979 180)
			(size 0.3 1.75)
			(layers "F.Cu" "F.Mask" "F.Paste")
			(net 5 "GND")
			(pinfunction "22")
			(pintype "passive")
		)
		(pad "23" smd rect
			(at 27.874 -12.176 180)
			(size 0.3 1.75)
			(layers "F.Cu" "F.Mask" "F.Paste")
			(net 5 "GND")
			(pinfunction "23")
			(pintype "passive")
		)
		(pad "24" smd rect
			(at 27.624 -3.979 180)
			(size 0.3 1.75)
			(layers "F.Cu" "F.Mask" "F.Paste")
			(net 5 "GND")
			(pinfunction "24")
			(pintype "passive")
		)
		(pad "25" smd rect
			(at 27.374 -12.176 180)
			(size 0.3 1.75)
			(layers "F.Cu" "F.Mask" "F.Paste")
			(net 5 "GND")
			(pinfunction "25")
			(pintype "passive")
		)
		(pad "26" smd rect
			(at 27.124 -3.979 180)
			(size 0.3 1.75)
			(layers "F.Cu" "F.Mask" "F.Paste")
			(net 5 "GND")
			(pinfunction "26")
			(pintype "passive")
		)
		(pad "27" smd rect
			(at 26.874 -12.176 180)
			(size 0.3 1.75)
			(layers "F.Cu" "F.Mask" "F.Paste")
			(net 5 "GND")
			(pinfunction "27")
			(pintype "passive")
		)
		(pad "28" smd rect
			(at 26.624 -3.979 180)
			(size 0.3 1.75)
			(layers "F.Cu" "F.Mask" "F.Paste")
			(net 5 "GND")
			(pinfunction "28")
			(pintype "passive")
		)
		(pad "29" smd rect
			(at 26.374 -12.176 180)
			(size 0.3 1.75)
			(layers "F.Cu" "F.Mask" "F.Paste")
			(net 5 "GND")
			(pinfunction "29")
			(pintype "passive")
		)
		(pad "30" smd rect
			(at 26.124 -3.979 180)
			(size 0.3 1.75)
			(layers "F.Cu" "F.Mask" "F.Paste")
			(net 5 "GND")
			(pinfunction "30")
			(pintype "passive")
		)
		(pad "31" smd rect
			(at 25.874 -12.176 180)
			(size 0.3 1.75)
			(layers "F.Cu" "F.Mask" "F.Paste")
			(net 5 "GND")
			(pinfunction "31")
			(pintype "passive")
		)
		(pad "32" smd rect
			(at 25.624 -3.979 180)
			(size 0.3 1.75)
			(layers "F.Cu" "F.Mask" "F.Paste")
			(net 5 "GND")
			(pinfunction "32")
			(pintype "passive")
		)
		(pad "33" smd rect
			(at 25.374 -12.176 180)
			(size 0.3 1.75)
			(layers "F.Cu" "F.Mask" "F.Paste")
			(net 5 "GND")
			(pinfunction "33")
			(pintype "passive")
		)
		(pad "34" smd rect
			(at 25.124 -3.979 180)
			(size 0.3 1.75)
			(layers "F.Cu" "F.Mask" "F.Paste")
			(net 5 "GND")
			(pinfunction "34")
			(pintype "passive")
		)
		(pad "35" smd rect
			(at 24.874 -12.176 180)
			(size 0.3 1.75)
			(layers "F.Cu" "F.Mask" "F.Paste")
			(net 5 "GND")
			(pinfunction "35")
			(pintype "passive")
		)
		(pad "36" smd rect
			(at 24.624 -3.979 180)
			(size 0.3 1.75)
			(layers "F.Cu" "F.Mask" "F.Paste")
			(net 5 "GND")
			(pinfunction "36")
			(pintype "passive")
		)
		(pad "37" smd rect
			(at 24.374 -12.176 180)
			(size 0.3 1.75)
			(layers "F.Cu" "F.Mask" "F.Paste")
			(net 5 "GND")
			(pinfunction "37")
			(pintype "passive")
		)
		(pad "38" smd rect
			(at 24.124 -3.979 180)
			(size 0.3 1.75)
			(layers "F.Cu" "F.Mask" "F.Paste")
			(net 5 "GND")
			(pinfunction "38")
			(pintype "passive")
		)
		(pad "39" smd rect
			(at 23.874 -12.176 180)
			(size 0.3 1.75)
			(layers "F.Cu" "F.Mask" "F.Paste")
			(net 5 "GND")
			(pinfunction "39")
			(pintype "passive")
		)
		(pad "40" smd rect
			(at 23.624 -3.979 180)
			(size 0.3 1.75)
			(layers "F.Cu" "F.Mask" "F.Paste")
			(net 5 "GND")
			(pinfunction "40")
			(pintype "passive")
		)
		(pad "41" smd rect
			(at 23.374 -12.176 180)
			(size 0.3 1.75)
			(layers "F.Cu" "F.Mask" "F.Paste")
			(net 5 "GND")
			(pinfunction "41")
			(pintype "passive")
		)
		(pad "42" smd rect
			(at 23.124 -3.979 180)
			(size 0.3 1.75)
			(layers "F.Cu" "F.Mask" "F.Paste")
			(net 5 "GND")
			(pinfunction "42")
			(pintype "passive")
		)
		(pad "43" smd rect
			(at 22.874 -12.176 180)
			(size 0.3 1.75)
			(layers "F.Cu" "F.Mask" "F.Paste")
			(net 5 "GND")
			(pinfunction "43")
			(pintype "passive")
		)
		(pad "44" smd rect
			(at 22.624 -3.979 180)
			(size 0.3 1.75)
			(layers "F.Cu" "F.Mask" "F.Paste")
			(net 5 "GND")
			(pinfunction "44")
			(pintype "passive")
		)
		(pad "45" smd rect
			(at 22.374 -12.176 180)
			(size 0.3 1.75)
			(layers "F.Cu" "F.Mask" "F.Paste")
			(net 5 "GND")
			(pinfunction "45")
			(pintype "passive")
		)
		(pad "46" smd rect
			(at 22.124 -3.979 180)
			(size 0.3 1.75)
			(layers "F.Cu" "F.Mask" "F.Paste")
			(net 5 "GND")
			(pinfunction "46")
			(pintype "passive")
		)
		(pad "47" smd rect
			(at 21.874 -12.176 180)
			(size 0.3 1.75)
			(layers "F.Cu" "F.Mask" "F.Paste")
			(net 5 "GND")
			(pinfunction "47")
			(pintype "passive")
		)
		(pad "48" smd rect
			(at 21.624 -3.979 180)
			(size 0.3 1.75)
			(layers "F.Cu" "F.Mask" "F.Paste")
			(net 5 "GND")
			(pinfunction "48")
			(pintype "passive")
		)
		(pad "49" smd rect
			(at 21.374 -12.176 180)
			(size 0.3 1.75)
			(layers "F.Cu" "F.Mask" "F.Paste")
			(net 5 "GND")
			(pinfunction "49")
			(pintype "passive")
		)
		(pad "50" smd rect
			(at 21.124 -3.979 180)
			(size 0.3 1.75)
			(layers "F.Cu" "F.Mask" "F.Paste")
			(net 5 "GND")
			(pinfunction "50")
			(pintype "passive")
		)
		(pad "51" smd rect
			(at 20.874 -12.176 180)
			(size 0.3 1.75)
			(layers "F.Cu" "F.Mask" "F.Paste")
			(net 91 "unconnected-(J9-Pad51)")
			(pinfunction "51")
			(pintype "passive+no_connect")
		)
		(pad "52" smd rect
			(at 20.624 -3.979 180)
			(size 0.3 1.75)
			(layers "F.Cu" "F.Mask" "F.Paste")
			(net 92 "unconnected-(J9-Pad52)")
			(pinfunction "52")
			(pintype "passive+no_connect")
		)
		(pad "53" smd rect
			(at 20.374 -12.176 180)
			(size 0.3 1.75)
			(layers "F.Cu" "F.Mask" "F.Paste")
			(net 93 "unconnected-(J9-Pad53)")
			(pinfunction "53")
			(pintype "passive+no_connect")
		)
		(pad "54" smd rect
			(at 20.124 -3.979 180)
			(size 0.3 1.75)
			(layers "F.Cu" "F.Mask" "F.Paste")
			(net 94 "unconnected-(J9-Pad54)")
			(pinfunction "54")
			(pintype "passive+no_connect")
		)
		(pad "55" smd rect
			(at 19.874 -12.176 180)
			(size 0.3 1.75)
			(layers "F.Cu" "F.Mask" "F.Paste")
			(net 96 "unconnected-(J9-Pad55)")
			(pinfunction "55")
			(pintype "passive+no_connect")
		)
		(pad "56" smd rect
			(at 19.624 -3.979 180)
			(size 0.3 1.75)
			(layers "F.Cu" "F.Mask" "F.Paste")
			(net 97 "unconnected-(J9-Pad56)")
			(pinfunction "56")
			(pintype "passive+no_connect")
		)
		(pad "57" smd rect
			(at 19.374 -12.176 180)
			(size 0.3 1.75)
			(layers "F.Cu" "F.Mask" "F.Paste")
			(net 98 "unconnected-(J9-Pad57)")
			(pinfunction "57")
			(pintype "passive+no_connect")
		)
		(pad "58" smd rect
			(at 19.124 -3.979 180)
			(size 0.3 1.75)
			(layers "F.Cu" "F.Mask" "F.Paste")
			(net 99 "unconnected-(J9-Pad58)")
			(pinfunction "58")
			(pintype "passive+no_connect")
		)
		(pad "59" smd rect
			(at 18.874 -12.176 180)
			(size 0.3 1.75)
			(layers "F.Cu" "F.Mask" "F.Paste")
			(net 100 "unconnected-(J9-Pad59)")
			(pinfunction "59")
			(pintype "passive+no_connect")
		)
		(pad "60" smd rect
			(at 18.624 -3.979 180)
			(size 0.3 1.75)
			(layers "F.Cu" "F.Mask" "F.Paste")
			(net 101 "unconnected-(J9-Pad60)")
			(pinfunction "60")
			(pintype "passive+no_connect")
		)
		(pad "61" smd rect
			(at 18.374 -12.176 180)
			(size 0.3 1.75)
			(layers "F.Cu" "F.Mask" "F.Paste")
			(net 102 "unconnected-(J9-Pad61)")
			(pinfunction "61")
			(pintype "passive+no_connect")
		)
		(pad "62" smd rect
			(at 18.124 -3.979 180)
			(size 0.3 1.75)
			(layers "F.Cu" "F.Mask" "F.Paste")
			(net 103 "unconnected-(J9-Pad62)")
			(pinfunction "62")
			(pintype "passive+no_connect")
		)
		(pad "63" smd rect
			(at 17.874 -12.176 180)
			(size 0.3 1.75)
			(layers "F.Cu" "F.Mask" "F.Paste")
			(net 104 "unconnected-(J9-Pad63)")
			(pinfunction "63")
			(pintype "passive+no_connect")
		)
		(pad "64" smd rect
			(at 17.624 -3.979 180)
			(size 0.3 1.75)
			(layers "F.Cu" "F.Mask" "F.Paste")
			(net 105 "unconnected-(J9-Pad64)")
			(pinfunction "64")
			(pintype "passive+no_connect")
		)
		(pad "65" smd rect
			(at 17.374 -12.176 180)
			(size 0.3 1.75)
			(layers "F.Cu" "F.Mask" "F.Paste")
			(net 106 "unconnected-(J9-Pad65)")
			(pinfunction "65")
			(pintype "passive+no_connect")
		)
		(pad "66" smd rect
			(at 17.124 -3.979 180)
			(size 0.3 1.75)
			(layers "F.Cu" "F.Mask" "F.Paste")
			(net 107 "unconnected-(J9-Pad66)")
			(pinfunction "66")
			(pintype "passive+no_connect")
		)
		(pad "67" smd rect
			(at 16.874 -12.176 180)
			(size 0.3 1.75)
			(layers "F.Cu" "F.Mask" "F.Paste")
			(net 108 "unconnected-(J9-Pad67)")
			(pinfunction "67")
			(pintype "passive+no_connect")
		)
		(pad "68" smd rect
			(at 16.624 -3.979 180)
			(size 0.3 1.75)
			(layers "F.Cu" "F.Mask" "F.Paste")
			(net 109 "unconnected-(J9-Pad68)")
			(pinfunction "68")
			(pintype "passive+no_connect")
		)
		(pad "69" smd rect
			(at 16.374 -12.176 180)
			(size 0.3 1.75)
			(layers "F.Cu" "F.Mask" "F.Paste")
			(net 110 "unconnected-(J9-Pad69)")
			(pinfunction "69")
			(pintype "passive+no_connect")
		)
		(pad "70" smd rect
			(at 16.124 -3.979 180)
			(size 0.3 1.75)
			(layers "F.Cu" "F.Mask" "F.Paste")
			(net 111 "unconnected-(J9-Pad70)")
			(pinfunction "70")
			(pintype "passive+no_connect")
		)
		(pad "71" smd rect
			(at 15.874 -12.176 180)
			(size 0.3 1.75)
			(layers "F.Cu" "F.Mask" "F.Paste")
			(net 112 "unconnected-(J9-Pad71)")
			(pinfunction "71")
			(pintype "passive+no_connect")
		)
		(pad "72" smd rect
			(at 15.624 -3.979 180)
			(size 0.3 1.75)
			(layers "F.Cu" "F.Mask" "F.Paste")
			(net 113 "unconnected-(J9-Pad72)")
			(pinfunction "72")
			(pintype "passive+no_connect")
		)
		(pad "73" smd rect
			(at 15.374 -12.176 180)
			(size 0.3 1.75)
			(layers "F.Cu" "F.Mask" "F.Paste")
			(net 114 "unconnected-(J9-Pad73)")
			(pinfunction "73")
			(pintype "passive+no_connect")
		)
		(pad "74" smd rect
			(at 15.124 -3.979 180)
			(size 0.3 1.75)
			(layers "F.Cu" "F.Mask" "F.Paste")
			(net 115 "unconnected-(J9-Pad74)")
			(pinfunction "74")
			(pintype "passive+no_connect")
		)
		(pad "75" smd rect
			(at 14.874 -12.176 180)
			(size 0.3 1.75)
			(layers "F.Cu" "F.Mask" "F.Paste")
			(net 116 "unconnected-(J9-Pad75)")
			(pinfunction "75")
			(pintype "passive+no_connect")
		)
		(pad "76" smd rect
			(at 14.624 -3.979 180)
			(size 0.3 1.75)
			(layers "F.Cu" "F.Mask" "F.Paste")
			(net 117 "unconnected-(J9-Pad76)")
			(pinfunction "76")
			(pintype "passive+no_connect")
		)
		(pad "77" smd rect
			(at 14.374 -12.176 180)
			(size 0.3 1.75)
			(layers "F.Cu" "F.Mask" "F.Paste")
			(net 118 "unconnected-(J9-Pad77)")
			(pinfunction "77")
			(pintype "passive+no_connect")
		)
		(pad "78" smd rect
			(at 14.124 -3.979 180)
			(size 0.3 1.75)
			(layers "F.Cu" "F.Mask" "F.Paste")
			(net 119 "unconnected-(J9-Pad78)")
			(pinfunction "78")
			(pintype "passive+no_connect")
		)
		(pad "79" smd rect
			(at 13.874 -12.176 180)
			(size 0.3 1.75)
			(layers "F.Cu" "F.Mask" "F.Paste")
			(net 120 "unconnected-(J9-Pad79)")
			(pinfunction "79")
			(pintype "passive+no_connect")
		)
		(pad "80" smd rect
			(at 13.624 -3.979 180)
			(size 0.3 1.75)
			(layers "F.Cu" "F.Mask" "F.Paste")
			(net 121 "unconnected-(J9-Pad80)")
			(pinfunction "80")
			(pintype "passive+no_connect")
		)
		(pad "81" smd rect
			(at 13.374 -12.176 180)
			(size 0.3 1.75)
			(layers "F.Cu" "F.Mask" "F.Paste")
			(net 122 "unconnected-(J9-Pad81)")
			(pinfunction "81")
			(pintype "passive+no_connect")
		)
		(pad "82" smd rect
			(at 13.124 -3.979 180)
			(size 0.3 1.75)
			(layers "F.Cu" "F.Mask" "F.Paste")
			(net 123 "unconnected-(J9-Pad82)")
			(pinfunction "82")
			(pintype "passive+no_connect")
		)
		(pad "83" smd rect
			(at 12.874 -12.176 180)
			(size 0.3 1.75)
			(layers "F.Cu" "F.Mask" "F.Paste")
			(net 124 "unconnected-(J9-Pad83)")
			(pinfunction "83")
			(pintype "passive+no_connect")
		)
		(pad "84" smd rect
			(at 12.624 -3.979 180)
			(size 0.3 1.75)
			(layers "F.Cu" "F.Mask" "F.Paste")
			(net 125 "unconnected-(J9-Pad84)")
			(pinfunction "84")
			(pintype "passive+no_connect")
		)
		(pad "85" smd rect
			(at 12.374 -12.176 180)
			(size 0.3 1.75)
			(layers "F.Cu" "F.Mask" "F.Paste")
			(net 126 "unconnected-(J9-Pad85)")
			(pinfunction "85")
			(pintype "passive+no_connect")
		)
		(pad "86" smd rect
			(at 12.124 -3.979 180)
			(size 0.3 1.75)
			(layers "F.Cu" "F.Mask" "F.Paste")
			(net 127 "unconnected-(J9-Pad86)")
			(pinfunction "86")
			(pintype "passive+no_connect")
		)
		(pad "87" smd rect
			(at 11.874 -12.176 180)
			(size 0.3 1.75)
			(layers "F.Cu" "F.Mask" "F.Paste")
			(net 128 "unconnected-(J9-Pad87)")
			(pinfunction "87")
			(pintype "passive+no_connect")
		)
		(pad "88" smd rect
			(at 11.624 -3.979 180)
			(size 0.3 1.75)
			(layers "F.Cu" "F.Mask" "F.Paste")
			(net 129 "unconnected-(J9-Pad88)")
			(pinfunction "88")
			(pintype "passive+no_connect")
		)
		(pad "89" smd rect
			(at 11.374 -12.176 180)
			(size 0.3 1.75)
			(layers "F.Cu" "F.Mask" "F.Paste")
			(net 130 "unconnected-(J9-Pad89)")
			(pinfunction "89")
			(pintype "passive+no_connect")
		)
	)
)
